(kicad_pcb
	(version 20260206)
	(generator "pcbnew")
	(generator_version "10.0")
	(general
		(thickness 1.6)
		(legacy_teardrops no)
	)
	(paper "A4")
	(title_block
		(title "panther-plus-userver — 13130-1b_20150205.brd")
		(comment 1 "Honey Badger (Wiwynn) / footprints 254-260 of 1509")
	)
	(layers
		(0 "F.Cu" signal "TOP")
		(4 "In1.Cu" signal "L2")
		(6 "In2.Cu" signal "L3")
		(8 "In3.Cu" signal "L4")
		(10 "In4.Cu" signal "L5")
		(12 "In5.Cu" signal "L6")
		(14 "In6.Cu" signal "L7")
		(16 "In7.Cu" signal "L8")
		(18 "In8.Cu" signal "L9")
		(20 "In9.Cu" signal "L10")
		(22 "In10.Cu" signal "L11")
		(2 "B.Cu" signal "BOTTOM")
		(9 "F.Adhes" user "F.Adhesive")
		(11 "B.Adhes" user "B.Adhesive")
		(13 "F.Paste" user "Package Geometry/Pastemask Top")
		(15 "B.Paste" user "Package Geometry/Pastemask Bottom")
		(5 "F.SilkS" user "Ref Des/Silkscreen Top")
		(7 "B.SilkS" user "Ref Des/Silkscreen Bottom")
		(1 "F.Mask" user "Board Geometry/Soldermask Top")
		(3 "B.Mask" user "Board Geometry/Soldermask Bottom")
		(17 "Dwgs.User" user "User.Drawings")
		(19 "Cmts.User" user "User.Comments")
		(21 "Eco1.User" user "User.Eco1")
		(23 "Eco2.User" user "User.Eco2")
		(25 "Edge.Cuts" user "Board Geometry/Outline")
		(27 "Margin" user)
		(31 "F.CrtYd" user "Package Geometry/Place Bound Top")
		(29 "B.CrtYd" user "Package Geometry/Place Bound Bottom")
		(35 "F.Fab" user "Ref Des/Assembly Top")
		(33 "B.Fab" user "Ref Des/Assembly Bottom")
	)
	(footprint ""
		(layer "F.Cu")
		(at 46.609 -47.498)
		(property "Reference" "C17"
			(at 0 0 0)
			(layer "F.SilkS")
			(hide yes)
			(effects
				(font
					(size 1.27 1.27)
				)
			)
		)
		(property "Value" "SCD47U25V2KX-GP"
			(at 1.8923 -1.2065 0)
			(unlocked yes)
			(layer "F.Fab")
			(hide yes)
			(effects
				(font
					(size 1.016 1.016)
					(thickness 0.1524)
				)
			)
		)
		(property "Device Type" "C402H24"
			(at 1.8923 -2.7305 0)
			(unlocked yes)
			(layer "F.Fab")
			(hide yes)
			(effects
				(font
					(size 1.016 1.016)
					(thickness 0.1524)
				)
			)
		)
		(duplicate_pad_numbers_are_jumpers no)
		(fp_rect
			(start -0.381 0.7366)
			(end 0.381 -0.7366)
			(stroke
				(width 0)
				(type default)
			)
			(fill no)
			(layer "F.CrtYd")
		)
		(fp_rect
			(start -0.381 0.7366)
			(end 0.381 -0.7366)
			(stroke
				(width 0)
				(type default)
			)
			(fill no)
			(layer "F.Fab")
		)
		(pad "1" smd custom
			(at 0 -0.4572)
			(size 0.1143 0.1143)
			(layers "F.Cu" "F.Mask" "F.Paste")
			(net "SW_P3V3_CPU_EN_LV_D")
			(options
				(clearance outline)
				(anchor circle)
			)
			(primitives
				(gr_poly
					(pts
						(arc
							(start -0.254 -0.1778)
							(mid -0.239121 -0.213721)
							(end -0.2032 -0.2286)
						)
						(arc
							(start 0.2032 -0.2286)
							(mid 0.239121 -0.213721)
							(end 0.254 -0.1778)
						)
						(arc
							(start 0.254 0.1778)
							(mid 0.239121 0.213721)
							(end 0.2032 0.2286)
						)
						(arc
							(start -0.2032 0.2286)
							(mid -0.239121 0.213721)
							(end -0.254 0.1778)
						)
					)
					(width 0)
					(fill yes)
				)
			)
		)
		(pad "2" smd custom
			(at 0 0.4572)
			(size 0.1143 0.1143)
			(layers "F.Cu" "F.Mask" "F.Paste")
			(net "P3V3_CPU")
			(options
				(clearance outline)
				(anchor circle)
			)
			(primitives
				(gr_poly
					(pts
						(arc
							(start -0.254 -0.1778)
							(mid -0.239121 -0.213721)
							(end -0.2032 -0.2286)
						)
						(arc
							(start 0.2032 -0.2286)
							(mid 0.239121 -0.213721)
							(end 0.254 -0.1778)
						)
						(arc
							(start 0.254 0.1778)
							(mid 0.239121 0.213721)
							(end 0.2032 0.2286)
						)
						(arc
							(start -0.2032 0.2286)
							(mid -0.239121 0.213721)
							(end -0.254 0.1778)
						)
					)
					(width 0)
					(fill yes)
				)
			)
		)
	)
	(footprint ""
		(layer "F.Cu")
		(at 55.499 -54.356 180)
		(property "Reference" "PC104"
			(at 0 0 180)
			(layer "F.SilkS")
			(hide yes)
			(effects
				(font
					(size 1.27 1.27)
				)
			)
		)
		(property "Value" "SC5P50V2CN-2GP"
			(at 1.8923 -1.2065 180)
			(unlocked yes)
			(layer "F.Fab")
			(hide yes)
			(effects
				(font
					(size 1.016 1.016)
					(thickness 0.1524)
				)
			)
		)
		(property "Device Type" "C402H22"
			(at 1.8923 -2.7305 180)
			(unlocked yes)
			(layer "F.Fab")
			(hide yes)
			(effects
				(font
					(size 1.016 1.016)
					(thickness 0.1524)
				)
			)
		)
		(duplicate_pad_numbers_are_jumpers no)
		(fp_rect
			(start -0.381 0.7366)
			(end 0.381 -0.7366)
			(stroke
				(width 0)
				(type default)
			)
			(fill no)
			(layer "F.CrtYd")
		)
		(fp_rect
			(start -0.381 0.7366)
			(end 0.381 -0.7366)
			(stroke
				(width 0)
				(type default)
			)
			(fill no)
			(layer "F.Fab")
		)
		(pad "1" smd custom
			(at 0 -0.4572 180)
			(size 0.1143 0.1143)
			(layers "F.Cu" "F.Mask" "F.Paste")
			(net "VR_FB_R_P1V0_STBY")
			(options
				(clearance outline)
				(anchor circle)
			)
			(primitives
				(gr_poly
					(pts
						(arc
							(start -0.254 -0.1778)
							(mid -0.239121 -0.213721)
							(end -0.2032 -0.2286)
						)
						(arc
							(start 0.2032 -0.2286)
							(mid 0.239121 -0.213721)
							(end 0.254 -0.1778)
						)
						(arc
							(start 0.254 0.1778)
							(mid 0.239121 0.213721)
							(end 0.2032 0.2286)
						)
						(arc
							(start -0.2032 0.2286)
							(mid -0.239121 0.213721)
							(end -0.254 0.1778)
						)
					)
					(width 0)
					(fill yes)
				)
			)
		)
		(pad "2" smd custom
			(at 0 0.4572 180)
			(size 0.1143 0.1143)
			(layers "F.Cu" "F.Mask" "F.Paste")
			(net "VR_FB_P1V0_STBY")
			(options
				(clearance outline)
				(anchor circle)
			)
			(primitives
				(gr_poly
					(pts
						(arc
							(start -0.254 -0.1778)
							(mid -0.239121 -0.213721)
							(end -0.2032 -0.2286)
						)
						(arc
							(start 0.2032 -0.2286)
							(mid 0.239121 -0.213721)
							(end 0.254 -0.1778)
						)
						(arc
							(start 0.254 0.1778)
							(mid 0.239121 0.213721)
							(end 0.2032 0.2286)
						)
						(arc
							(start -0.2032 0.2286)
							(mid -0.239121 0.213721)
							(end -0.254 0.1778)
						)
					)
					(width 0)
					(fill yes)
				)
			)
		)
	)
	(footprint ""
		(layer "F.Cu")
		(at 43.688 -61.214 -90)
		(property "Reference" "PR51"
			(at 0 0 270)
			(layer "F.SilkS")
			(hide yes)
			(effects
				(font
					(size 1.27 1.27)
				)
			)
		)
		(property "Value" "10KR2F-2-GP"
			(at 1.7907 -1.1176 270)
			(unlocked yes)
			(layer "F.Fab")
			(hide yes)
			(effects
				(font
					(size 1.016 1.016)
					(thickness 0.1524)
				)
			)
		)
		(property "Device Type" "R402H16"
			(at 1.7907 -2.6416 270)
			(unlocked yes)
			(layer "F.Fab")
			(hide yes)
			(effects
				(font
					(size 1.016 1.016)
					(thickness 0.1524)
				)
			)
		)
		(duplicate_pad_numbers_are_jumpers no)
		(fp_rect
			(start -0.381 0.8382)
			(end 0.381 -0.8382)
			(stroke
				(width 0)
				(type default)
			)
			(fill no)
			(layer "F.CrtYd")
		)
		(fp_rect
			(start -0.381 0.8382)
			(end 0.381 -0.8382)
			(stroke
				(width 0)
				(type default)
			)
			(fill no)
			(layer "F.Fab")
		)
		(pad "1" smd custom
			(at 0 -0.4318 270)
			(size 0.127 0.127)
			(layers "F.Cu" "F.Mask" "F.Paste")
			(net "GND")
			(options
				(clearance outline)
				(anchor circle)
			)
			(primitives
				(gr_poly
					(pts
						(arc
							(start -0.2032 -0.2794)
							(mid -0.239121 -0.264521)
							(end -0.254 -0.2286)
						)
						(arc
							(start -0.254 0.2286)
							(mid -0.239121 0.264521)
							(end -0.2032 0.2794)
						)
						(arc
							(start 0.2032 0.2794)
							(mid 0.239121 0.264521)
							(end 0.254 0.2286)
						)
						(arc
							(start 0.254 -0.2286)
							(mid 0.239121 -0.264521)
							(end 0.2032 -0.2794)
						)
					)
					(width 0)
					(fill yes)
				)
			)
		)
		(pad "2" smd custom
			(at 0 0.4318 270)
			(size 0.127 0.127)
			(layers "F.Cu" "F.Mask" "F.Paste")
			(net "VR_PVCCP_LH_R")
			(options
				(clearance outline)
				(anchor circle)
			)
			(primitives
				(gr_poly
					(pts
						(arc
							(start -0.2032 -0.2794)
							(mid -0.239121 -0.264521)
							(end -0.254 -0.2286)
						)
						(arc
							(start -0.254 0.2286)
							(mid -0.239121 0.264521)
							(end -0.2032 0.2794)
						)
						(arc
							(start 0.2032 0.2794)
							(mid 0.239121 0.264521)
							(end 0.254 0.2286)
						)
						(arc
							(start 0.254 -0.2286)
							(mid 0.239121 -0.264521)
							(end 0.2032 -0.2794)
						)
					)
					(width 0)
					(fill yes)
				)
			)
		)
	)
	(footprint ""
		(layer "F.Cu")
		(at 44.323 -46.99 180)
		(property "Reference" "Q3"
			(at 0 0 180)
			(layer "F.SilkS")
			(hide yes)
			(effects
				(font
					(size 1.27 1.27)
				)
			)
		)
		(property "Value" "FDN359BN-GP-U"
			(at -3.175 0.254 180)
			(unlocked yes)
			(layer "F.Fab")
			(hide yes)
			(effects
				(font
					(size 1.016 1.016)
					(thickness 0.1524)
				)
			)
		)
		(property "Device Type" "SOT23DGS2D6H45"
			(at -3.175 -1.27 180)
			(unlocked yes)
			(layer "F.Fab")
			(hide yes)
			(effects
				(font
					(size 1.016 1.016)
					(thickness 0.1524)
				)
			)
		)
		(duplicate_pad_numbers_are_jumpers no)
		(fp_line
			(start 1.7145 0.2794)
			(end 1.7145 -0.2794)
			(stroke
				(width 0.1524)
				(type default)
			)
			(layer "F.SilkS")
		)
		(fp_line
			(start 1.7145 -0.2794)
			(end -1.7145 -0.2794)
			(stroke
				(width 0.1524)
				(type default)
			)
			(layer "F.SilkS")
		)
		(fp_line
			(start -1.7145 0.2794)
			(end 1.7145 0.2794)
			(stroke
				(width 0.1524)
				(type default)
			)
			(layer "F.SilkS")
		)
		(fp_line
			(start -1.7145 -0.2794)
			(end -1.7145 0.2794)
			(stroke
				(width 0.1524)
				(type default)
			)
			(layer "F.SilkS")
		)
		(fp_rect
			(start -1.7145 1.651)
			(end 1.7145 -1.651)
			(stroke
				(width 0)
				(type default)
			)
			(fill no)
			(layer "F.CrtYd")
		)
		(fp_rect
			(start -1.7145 1.651)
			(end 1.7145 -1.651)
			(stroke
				(width 0)
				(type default)
			)
			(fill no)
			(layer "F.Fab")
		)
		(pad "D" smd custom
			(at 0 -1.016 180)
			(size 0.1651 0.1651)
			(layers "F.Cu" "F.Mask" "F.Paste")
			(net "P3V3_STBY")
			(options
				(clearance outline)
				(anchor circle)
			)
			(primitives
				(gr_poly
					(pts
						(arc
							(start -0.127 0.508)
							(mid -0.270684 0.448484)
							(end -0.3302 0.3048)
						)
						(arc
							(start -0.3302 -0.3048)
							(mid -0.270684 -0.448484)
							(end -0.127 -0.508)
						)
						(arc
							(start 0.127 -0.508)
							(mid 0.270684 -0.448484)
							(end 0.3302 -0.3048)
						)
						(arc
							(start 0.3302 0.3048)
							(mid 0.270684 0.448484)
							(end 0.127 0.508)
						)
					)
					(width 0)
					(fill yes)
				)
			)
		)
		(pad "G" smd custom
			(at -0.94996 1.016 180)
			(size 0.1651 0.1651)
			(layers "F.Cu" "F.Mask" "F.Paste")
			(net "SW_P3V3_CPU_EN_LV_D")
			(options
				(clearance outline)
				(anchor circle)
			)
			(primitives
				(gr_poly
					(pts
						(arc
							(start -0.127 0.508)
							(mid -0.270684 0.448484)
							(end -0.3302 0.3048)
						)
						(arc
							(start -0.3302 -0.3048)
							(mid -0.270684 -0.448484)
							(end -0.127 -0.508)
						)
						(arc
							(start 0.127 -0.508)
							(mid 0.270684 -0.448484)
							(end 0.3302 -0.3048)
						)
						(arc
							(start 0.3302 0.3048)
							(mid 0.270684 0.448484)
							(end 0.127 0.508)
						)
					)
					(width 0)
					(fill yes)
				)
			)
		)
		(pad "S" smd custom
			(at 0.94996 1.016 180)
			(size 0.1651 0.1651)
			(layers "F.Cu" "F.Mask" "F.Paste")
			(net "P3V3_CPU")
			(options
				(clearance outline)
				(anchor circle)
			)
			(primitives
				(gr_poly
					(pts
						(arc
							(start -0.127 0.508)
							(mid -0.270684 0.448484)
							(end -0.3302 0.3048)
						)
						(arc
							(start -0.3302 -0.3048)
							(mid -0.270684 -0.448484)
							(end -0.127 -0.508)
						)
						(arc
							(start 0.127 -0.508)
							(mid 0.270684 -0.448484)
							(end 0.3302 -0.3048)
						)
						(arc
							(start 0.3302 0.3048)
							(mid 0.270684 0.448484)
							(end 0.127 0.508)
						)
					)
					(width 0)
					(fill yes)
				)
			)
		)
	)
	(footprint ""
		(layer "F.Cu")
		(at 50.3428 -50.800254)
		(property "Reference" "L14"
			(at 0 0 0)
			(layer "F.SilkS")
			(hide yes)
			(effects
				(font
					(size 1.27 1.27)
				)
			)
		)
		(property "Value" "BLM18PG330SN1D-GP"
			(at -0.0254 -2.0193 0)
			(unlocked yes)
			(layer "F.Fab")
			(hide yes)
			(effects
				(font
					(size 1.016 1.016)
					(thickness 0.1524)
				)
			)
		)
		(property "Device Type" "L1608-UH38"
			(at -0.0254 -3.5433 0)
			(unlocked yes)
			(layer "F.Fab")
			(hide yes)
			(effects
				(font
					(size 1.016 1.016)
					(thickness 0.1524)
				)
			)
		)
		(duplicate_pad_numbers_are_jumpers no)
		(fp_line
			(start -0.4064 0)
			(end 0.4064 0)
			(stroke
				(width 0.2032)
				(type default)
			)
			(layer "F.SilkS")
		)
		(fp_rect
			(start -0.635 1.1811)
			(end 0.635 -1.1811)
			(stroke
				(width 0)
				(type default)
			)
			(fill no)
			(layer "F.CrtYd")
		)
		(fp_rect
			(start -0.635 1.1811)
			(end 0.635 -1.1811)
			(stroke
				(width 0)
				(type default)
			)
			(fill no)
			(layer "F.Fab")
		)
		(pad "1" smd custom
			(at 0 -0.6604)
			(size 0.19685 0.19685)
			(layers "F.Cu" "F.Mask" "F.Paste")
			(net "P1V5_STBY")
			(options
				(clearance outline)
				(anchor circle)
			)
			(primitives
				(gr_poly
					(pts
						(arc
							(start 0.508 -0.2921)
							(mid 0.478242 -0.363942)
							(end 0.4064 -0.3937)
						)
						(arc
							(start -0.4064 -0.3937)
							(mid -0.478242 -0.363942)
							(end -0.508 -0.2921)
						)
						(arc
							(start -0.508 0.2921)
							(mid -0.478242 0.363942)
							(end -0.4064 0.3937)
						)
						(arc
							(start 0.4064 0.3937)
							(mid 0.478242 0.363942)
							(end 0.508 0.2921)
						)
					)
					(width 0)
					(fill yes)
				)
			)
		)
		(pad "2" smd custom
			(at 0 0.6604)
			(size 0.19685 0.19685)
			(layers "F.Cu" "F.Mask" "F.Paste")
			(net "P1V5_CLK_SCR_LVIO")
			(options
				(clearance outline)
				(anchor circle)
			)
			(primitives
				(gr_poly
					(pts
						(arc
							(start 0.508 -0.2921)
							(mid 0.478242 -0.363942)
							(end 0.4064 -0.3937)
						)
						(arc
							(start -0.4064 -0.3937)
							(mid -0.478242 -0.363942)
							(end -0.508 -0.2921)
						)
						(arc
							(start -0.508 0.2921)
							(mid -0.478242 0.363942)
							(end -0.4064 0.3937)
						)
						(arc
							(start 0.4064 0.3937)
							(mid 0.478242 0.363942)
							(end 0.508 0.2921)
						)
					)
					(width 0)
					(fill yes)
				)
			)
		)
	)
	(footprint ""
		(layer "F.Cu")
		(at 68.58 -43.18 90)
		(property "Reference" "R50"
			(at 0 0 90)
			(layer "F.SilkS")
			(hide yes)
			(effects
				(font
					(size 1.27 1.27)
				)
			)
		)
		(property "Value" "0R2J-2-GP"
			(at 0.064008 -3.993896 90)
			(unlocked yes)
			(layer "F.Fab")
			(hide yes)
			(effects
				(font
					(size 1.016 1.016)
					(thickness 0.1524)
				)
			)
		)
		(property "Device Type" "R402H16"
			(at 0.064008 -5.517896 90)
			(unlocked yes)
			(layer "F.Fab")
			(hide yes)
			(effects
				(font
					(size 1.016 1.016)
					(thickness 0.1524)
				)
			)
		)
		(duplicate_pad_numbers_are_jumpers no)
		(fp_rect
			(start -0.381 0.8382)
			(end 0.381 -0.8382)
			(stroke
				(width 0)
				(type default)
			)
			(fill no)
			(layer "F.CrtYd")
		)
		(fp_rect
			(start -0.381 0.8382)
			(end 0.381 -0.8382)
			(stroke
				(width 0)
				(type default)
			)
			(fill no)
			(layer "F.Fab")
		)
		(pad "1" smd custom
			(at 0 -0.4318 90)
			(size 0.127 0.127)
			(layers "F.Cu" "F.Mask" "F.Paste")
			(net "SMBUS_PECI_R_DATA")
			(options
				(clearance outline)
				(anchor circle)
			)
			(primitives
				(gr_poly
					(pts
						(arc
							(start -0.2032 -0.2794)
							(mid -0.239121 -0.264521)
							(end -0.254 -0.2286)
						)
						(arc
							(start -0.254 0.2286)
							(mid -0.239121 0.264521)
							(end -0.2032 0.2794)
						)
						(arc
							(start 0.2032 0.2794)
							(mid 0.239121 0.264521)
							(end 0.254 0.2286)
						)
						(arc
							(start 0.254 -0.2286)
							(mid 0.239121 -0.264521)
							(end 0.2032 -0.2794)
						)
					)
					(width 0)
					(fill yes)
				)
			)
		)
		(pad "2" smd custom
			(at 0 0.4318 90)
			(size 0.127 0.127)
			(layers "F.Cu" "F.Mask" "F.Paste")
			(net "SMBUS_PECI_DATA")
			(options
				(clearance outline)
				(anchor circle)
			)
			(primitives
				(gr_poly
					(pts
						(arc
							(start -0.2032 -0.2794)
							(mid -0.239121 -0.264521)
							(end -0.254 -0.2286)
						)
						(arc
							(start -0.254 0.2286)
							(mid -0.239121 0.264521)
							(end -0.2032 0.2794)
						)
						(arc
							(start 0.2032 0.2794)
							(mid 0.239121 0.264521)
							(end 0.254 0.2286)
						)
						(arc
							(start 0.254 -0.2286)
							(mid 0.239121 -0.264521)
							(end 0.2032 -0.2794)
						)
					)
					(width 0)
					(fill yes)
				)
			)
		)
	)
	(footprint ""
		(layer "F.Cu")
		(at 151.765 -59.309)
		(property "Reference" "C326"
			(at 0 0 0)
			(layer "F.SilkS")
			(hide yes)
			(effects
				(font
					(size 1.27 1.27)
				)
			)
		)
		(property "Value" "SCD1U16V2KX-3GP"
			(at 1.8923 -1.2065 0)
			(unlocked yes)
			(layer "F.Fab")
			(hide yes)
			(effects
				(font
					(size 1.016 1.016)
					(thickness 0.1524)
				)
			)
		)
		(property "Device Type" "C402H22"
			(at 1.8923 -2.7305 0)
			(unlocked yes)
			(layer "F.Fab")
			(hide yes)
			(effects
				(font
					(size 1.016 1.016)
					(thickness 0.1524)
				)
			)
		)
		(duplicate_pad_numbers_are_jumpers no)
		(fp_rect
			(start -0.381 0.7366)
			(end 0.381 -0.7366)
			(stroke
				(width 0)
				(type default)
			)
			(fill no)
			(layer "F.CrtYd")
		)
		(fp_rect
			(start -0.381 0.7366)
			(end 0.381 -0.7366)
			(stroke
				(width 0)
				(type default)
			)
			(fill no)
			(layer "F.Fab")
		)
		(pad "1" smd custom
			(at 0 -0.4572)
			(size 0.1143 0.1143)
			(layers "F.Cu" "F.Mask" "F.Paste")
			(net "PV_VDDR")
			(options
				(clearance outline)
				(anchor circle)
			)
			(primitives
				(gr_poly
					(pts
						(arc
							(start -0.254 -0.1778)
							(mid -0.239121 -0.213721)
							(end -0.2032 -0.2286)
						)
						(arc
							(start 0.2032 -0.2286)
							(mid 0.239121 -0.213721)
							(end 0.254 -0.1778)
						)
						(arc
							(start 0.254 0.1778)
							(mid 0.239121 0.213721)
							(end 0.2032 0.2286)
						)
						(arc
							(start -0.2032 0.2286)
							(mid -0.239121 0.213721)
							(end -0.254 0.1778)
						)
					)
					(width 0)
					(fill yes)
				)
			)
		)
		(pad "2" smd custom
			(at 0 0.4572)
			(size 0.1143 0.1143)
			(layers "F.Cu" "F.Mask" "F.Paste")
			(net "GND")
			(options
				(clearance outline)
				(anchor circle)
			)
			(primitives
				(gr_poly
					(pts
						(arc
							(start -0.254 -0.1778)
							(mid -0.239121 -0.213721)
							(end -0.2032 -0.2286)
						)
						(arc
							(start 0.2032 -0.2286)
							(mid 0.239121 -0.213721)
							(end 0.254 -0.1778)
						)
						(arc
							(start 0.254 0.1778)
							(mid 0.239121 0.213721)
							(end 0.2032 0.2286)
						)
						(arc
							(start -0.2032 0.2286)
							(mid -0.239121 0.213721)
							(end -0.254 0.1778)
						)
					)
					(width 0)
					(fill yes)
				)
			)
		)
	)
)
